(kicad_pcb
	(version 20260206)
	(generator "pcbnew")
	(generator_version "10.0")
	(general
		(thickness 1.6)
		(legacy_teardrops no)
	)
	(paper "A4")
	(title_block
		(title "01162023_DA0F0TEBIF0_F0T_Expander_BD_F_brd_V02_OCP.brd")
		(comment 1 "Grand Teton / footprints 1823-1829 of 9728")
	)
	(layers
		(0 "F.Cu" signal "TOP")
		(4 "In1.Cu" signal "GND")
		(6 "In2.Cu" signal "VCC")
		(8 "In3.Cu" signal "VCC1")
		(10 "In4.Cu" signal "GND1")
		(12 "In5.Cu" signal "IN1")
		(14 "In6.Cu" signal "GND2")
		(16 "In7.Cu" signal "IN2")
		(18 "In8.Cu" signal "GND3")
		(20 "In9.Cu" signal "IN3")
		(22 "In10.Cu" signal "GND4")
		(24 "In11.Cu" signal "IN4")
		(26 "In12.Cu" signal "GND5")
		(28 "In13.Cu" signal "IN5")
		(30 "In14.Cu" signal "GND6")
		(32 "In15.Cu" signal "IN6")
		(34 "In16.Cu" signal "GND7")
		(2 "B.Cu" signal "BOTTOM")
		(9 "F.Adhes" user "F.Adhesive")
		(11 "B.Adhes" user "B.Adhesive")
		(13 "F.Paste" user "Package Geometry/Pastemask Top")
		(15 "B.Paste" user "Package Geometry/Pastemask Bottom")
		(5 "F.SilkS" user "Ref Des/Silkscreen Top")
		(7 "B.SilkS" user "Ref Des/Silkscreen Bottom")
		(1 "F.Mask" user "Board Geometry/Soldermask Top")
		(3 "B.Mask" user "Board Geometry/Soldermask Bottom")
		(17 "Dwgs.User" user "User.Drawings")
		(19 "Cmts.User" user "User.Comments")
		(21 "Eco1.User" user "User.Eco1")
		(23 "Eco2.User" user "User.Eco2")
		(25 "Edge.Cuts" user "Board Geometry/Outline")
		(27 "Margin" user)
		(31 "F.CrtYd" user "Package Geometry/Place Bound Top")
		(29 "B.CrtYd" user "Package Geometry/Place Bound Bottom")
		(35 "F.Fab" user "Ref Des/Assembly Top")
		(33 "B.Fab" user "Ref Des/Assembly Bottom")
	)
	(footprint ""
		(layer "F.Cu")
		(at 344.511884 -112.547654)
		(property "Reference" "PC817"
			(at 0 0 0)
			(layer "F.SilkS")
			(hide yes)
			(effects
				(font
					(size 1.27 1.27)
				)
			)
		)
		(property "Value" ""
			(at 0 0 0)
			(layer "F.Fab")
			(effects
				(font
					(size 1.27 1.27)
				)
			)
		)
		(duplicate_pad_numbers_are_jumpers no)
		(fp_line
			(start -0.7874 -0.4064)
			(end 0.7874 -0.4064)
			(stroke
				(width 0.1524)
				(type default)
			)
			(layer "F.SilkS")
		)
		(fp_line
			(start -0.7874 0.4064)
			(end -0.7874 -0.4064)
			(stroke
				(width 0.1524)
				(type default)
			)
			(layer "F.SilkS")
		)
		(fp_line
			(start 0.7874 -0.4064)
			(end 0.7874 0.4064)
			(stroke
				(width 0.1524)
				(type default)
			)
			(layer "F.SilkS")
		)
		(fp_line
			(start 0.7874 0.4064)
			(end -0.7874 0.4064)
			(stroke
				(width 0.1524)
				(type default)
			)
			(layer "F.SilkS")
		)
		(fp_line
			(start -0.67945 -0.305054)
			(end -0.12065 -0.305054)
			(stroke
				(width 0.1)
				(type default)
			)
			(layer "F.Fab")
		)
		(fp_line
			(start -0.67945 0.3048)
			(end -0.67945 -0.305054)
			(stroke
				(width 0.1)
				(type default)
			)
			(layer "F.Fab")
		)
		(fp_line
			(start -0.12065 -0.305054)
			(end -0.12065 -0.2794)
			(stroke
				(width 0.1)
				(type default)
			)
			(layer "F.Fab")
		)
		(fp_line
			(start -0.12065 -0.2794)
			(end 0.12065 -0.2794)
			(stroke
				(width 0.1)
				(type default)
			)
			(layer "F.Fab")
		)
		(fp_line
			(start -0.12065 0.2794)
			(end -0.12065 0.3048)
			(stroke
				(width 0.1)
				(type default)
			)
			(layer "F.Fab")
		)
		(fp_line
			(start -0.12065 0.3048)
			(end -0.67945 0.3048)
			(stroke
				(width 0.1)
				(type default)
			)
			(layer "F.Fab")
		)
		(fp_line
			(start 0.120396 0.2794)
			(end -0.12065 0.2794)
			(stroke
				(width 0.1)
				(type default)
			)
			(layer "F.Fab")
		)
		(fp_line
			(start 0.120396 0.3048)
			(end 0.120396 0.2794)
			(stroke
				(width 0.1)
				(type default)
			)
			(layer "F.Fab")
		)
		(fp_line
			(start 0.12065 -0.3048)
			(end 0.67945 -0.3048)
			(stroke
				(width 0.1)
				(type default)
			)
			(layer "F.Fab")
		)
		(fp_line
			(start 0.12065 -0.2794)
			(end 0.12065 -0.3048)
			(stroke
				(width 0.1)
				(type default)
			)
			(layer "F.Fab")
		)
		(fp_line
			(start 0.67945 -0.3048)
			(end 0.67945 0.3048)
			(stroke
				(width 0.1)
				(type default)
			)
			(layer "F.Fab")
		)
		(fp_line
			(start 0.67945 0.3048)
			(end 0.120396 0.3048)
			(stroke
				(width 0.1)
				(type default)
			)
			(layer "F.Fab")
		)
		(pad "1" smd circle
			(at -0.40005 0)
			(size 0 0)
			(layers "F.Cu" "F.Mask" "F.Paste")
			(net "P12V_NIC5_CO_ISET_R")
		)
		(pad "2" smd circle
			(at 0.40005 0)
			(size 0 0)
			(layers "F.Cu" "F.Mask" "F.Paste")
			(net "GND")
		)
	)
	(footprint ""
		(layer "F.Cu")
		(at 347.842586 -257.13055 180)
		(property "Reference" "PC136"
			(at 0 0 180)
			(layer "F.SilkS")
			(hide yes)
			(effects
				(font
					(size 1.27 1.27)
				)
			)
		)
		(property "Value" ""
			(at 0 0 180)
			(layer "F.Fab")
			(effects
				(font
					(size 1.27 1.27)
				)
			)
		)
		(duplicate_pad_numbers_are_jumpers no)
		(fp_line
			(start 0.7874 0.4064)
			(end -0.7874 0.4064)
			(stroke
				(width 0.1524)
				(type default)
			)
			(layer "F.SilkS")
		)
		(fp_line
			(start 0.7874 -0.4064)
			(end 0.7874 0.4064)
			(stroke
				(width 0.1524)
				(type default)
			)
			(layer "F.SilkS")
		)
		(fp_line
			(start -0.7874 0.4064)
			(end -0.7874 -0.4064)
			(stroke
				(width 0.1524)
				(type default)
			)
			(layer "F.SilkS")
		)
		(fp_line
			(start -0.7874 -0.4064)
			(end 0.7874 -0.4064)
			(stroke
				(width 0.1524)
				(type default)
			)
			(layer "F.SilkS")
		)
		(fp_line
			(start 0.67945 0.3048)
			(end 0.120396 0.3048)
			(stroke
				(width 0.1)
				(type default)
			)
			(layer "F.Fab")
		)
		(fp_line
			(start 0.67945 -0.3048)
			(end 0.67945 0.3048)
			(stroke
				(width 0.1)
				(type default)
			)
			(layer "F.Fab")
		)
		(fp_line
			(start 0.12065 -0.2794)
			(end 0.12065 -0.3048)
			(stroke
				(width 0.1)
				(type default)
			)
			(layer "F.Fab")
		)
		(fp_line
			(start 0.12065 -0.3048)
			(end 0.67945 -0.3048)
			(stroke
				(width 0.1)
				(type default)
			)
			(layer "F.Fab")
		)
		(fp_line
			(start 0.120396 0.3048)
			(end 0.120396 0.2794)
			(stroke
				(width 0.1)
				(type default)
			)
			(layer "F.Fab")
		)
		(fp_line
			(start 0.120396 0.2794)
			(end -0.12065 0.2794)
			(stroke
				(width 0.1)
				(type default)
			)
			(layer "F.Fab")
		)
		(fp_line
			(start -0.12065 0.3048)
			(end -0.67945 0.3048)
			(stroke
				(width 0.1)
				(type default)
			)
			(layer "F.Fab")
		)
		(fp_line
			(start -0.12065 0.2794)
			(end -0.12065 0.3048)
			(stroke
				(width 0.1)
				(type default)
			)
			(layer "F.Fab")
		)
		(fp_line
			(start -0.12065 -0.2794)
			(end 0.12065 -0.2794)
			(stroke
				(width 0.1)
				(type default)
			)
			(layer "F.Fab")
		)
		(fp_line
			(start -0.12065 -0.305054)
			(end -0.12065 -0.2794)
			(stroke
				(width 0.1)
				(type default)
			)
			(layer "F.Fab")
		)
		(fp_line
			(start -0.67945 0.3048)
			(end -0.67945 -0.305054)
			(stroke
				(width 0.1)
				(type default)
			)
			(layer "F.Fab")
		)
		(fp_line
			(start -0.67945 -0.305054)
			(end -0.12065 -0.305054)
			(stroke
				(width 0.1)
				(type default)
			)
			(layer "F.Fab")
		)
		(pad "1" smd circle
			(at -0.40005 0 180)
			(size 0 0)
			(layers "F.Cu" "F.Mask" "F.Paste")
			(net "P0V8_PEX2_VINSEN")
		)
		(pad "2" smd circle
			(at 0.40005 0 180)
			(size 0 0)
			(layers "F.Cu" "F.Mask" "F.Paste")
			(net "GND")
		)
	)
	(footprint ""
		(layer "F.Cu")
		(at 266.683744 -336.197194)
		(property "Reference" "C4484"
			(at 0 0 0)
			(layer "F.SilkS")
			(hide yes)
			(effects
				(font
					(size 1.27 1.27)
				)
			)
		)
		(property "Value" ""
			(at 0 0 0)
			(layer "F.Fab")
			(effects
				(font
					(size 1.27 1.27)
				)
			)
		)
		(duplicate_pad_numbers_are_jumpers no)
		(fp_line
			(start -0.7874 -0.4064)
			(end 0.7874 -0.4064)
			(stroke
				(width 0.1524)
				(type default)
			)
			(layer "F.SilkS")
		)
		(fp_line
			(start -0.7874 0.4064)
			(end -0.7874 -0.4064)
			(stroke
				(width 0.1524)
				(type default)
			)
			(layer "F.SilkS")
		)
		(fp_line
			(start 0.7874 -0.4064)
			(end 0.7874 0.4064)
			(stroke
				(width 0.1524)
				(type default)
			)
			(layer "F.SilkS")
		)
		(fp_line
			(start 0.7874 0.4064)
			(end -0.7874 0.4064)
			(stroke
				(width 0.1524)
				(type default)
			)
			(layer "F.SilkS")
		)
		(fp_line
			(start -0.67945 -0.305054)
			(end -0.12065 -0.305054)
			(stroke
				(width 0.1)
				(type default)
			)
			(layer "F.Fab")
		)
		(fp_line
			(start -0.67945 0.3048)
			(end -0.67945 -0.305054)
			(stroke
				(width 0.1)
				(type default)
			)
			(layer "F.Fab")
		)
		(fp_line
			(start -0.12065 -0.305054)
			(end -0.12065 -0.2794)
			(stroke
				(width 0.1)
				(type default)
			)
			(layer "F.Fab")
		)
		(fp_line
			(start -0.12065 -0.2794)
			(end 0.12065 -0.2794)
			(stroke
				(width 0.1)
				(type default)
			)
			(layer "F.Fab")
		)
		(fp_line
			(start -0.12065 0.2794)
			(end -0.12065 0.3048)
			(stroke
				(width 0.1)
				(type default)
			)
			(layer "F.Fab")
		)
		(fp_line
			(start -0.12065 0.3048)
			(end -0.67945 0.3048)
			(stroke
				(width 0.1)
				(type default)
			)
			(layer "F.Fab")
		)
		(fp_line
			(start 0.120396 0.2794)
			(end -0.12065 0.2794)
			(stroke
				(width 0.1)
				(type default)
			)
			(layer "F.Fab")
		)
		(fp_line
			(start 0.120396 0.3048)
			(end 0.120396 0.2794)
			(stroke
				(width 0.1)
				(type default)
			)
			(layer "F.Fab")
		)
		(fp_line
			(start 0.12065 -0.3048)
			(end 0.67945 -0.3048)
			(stroke
				(width 0.1)
				(type default)
			)
			(layer "F.Fab")
		)
		(fp_line
			(start 0.12065 -0.2794)
			(end 0.12065 -0.3048)
			(stroke
				(width 0.1)
				(type default)
			)
			(layer "F.Fab")
		)
		(fp_line
			(start 0.67945 -0.3048)
			(end 0.67945 0.3048)
			(stroke
				(width 0.1)
				(type default)
			)
			(layer "F.Fab")
		)
		(fp_line
			(start 0.67945 0.3048)
			(end 0.120396 0.3048)
			(stroke
				(width 0.1)
				(type default)
			)
			(layer "F.Fab")
		)
		(pad "1" smd circle
			(at -0.40005 0)
			(size 0 0)
			(layers "F.Cu" "F.Mask" "F.Paste")
			(net "P12V_AUX")
		)
		(pad "2" smd circle
			(at 0.40005 0)
			(size 0 0)
			(layers "F.Cu" "F.Mask" "F.Paste")
			(net "GND")
		)
	)
	(footprint ""
		(layer "F.Cu")
		(at 228.79304 -92.041726 180)
		(property "Reference" "R1022"
			(at 0 0 180)
			(layer "F.SilkS")
			(hide yes)
			(effects
				(font
					(size 1.27 1.27)
				)
			)
		)
		(property "Value" ""
			(at 0 0 180)
			(layer "F.Fab")
			(effects
				(font
					(size 1.27 1.27)
				)
			)
		)
		(duplicate_pad_numbers_are_jumpers no)
		(fp_line
			(start 0.7874 0.4064)
			(end -0.7874 0.4064)
			(stroke
				(width 0.1524)
				(type default)
			)
			(layer "F.SilkS")
		)
		(fp_line
			(start 0.7874 -0.4064)
			(end 0.7874 0.4064)
			(stroke
				(width 0.1524)
				(type default)
			)
			(layer "F.SilkS")
		)
		(fp_line
			(start -0.7874 0.4064)
			(end -0.7874 -0.4064)
			(stroke
				(width 0.1524)
				(type default)
			)
			(layer "F.SilkS")
		)
		(fp_line
			(start -0.7874 -0.4064)
			(end 0.7874 -0.4064)
			(stroke
				(width 0.1524)
				(type default)
			)
			(layer "F.SilkS")
		)
		(fp_line
			(start 0.67945 0.3048)
			(end 0.120396 0.3048)
			(stroke
				(width 0.1)
				(type default)
			)
			(layer "F.Fab")
		)
		(fp_line
			(start 0.67945 -0.3048)
			(end 0.67945 0.3048)
			(stroke
				(width 0.1)
				(type default)
			)
			(layer "F.Fab")
		)
		(fp_line
			(start 0.12065 -0.2794)
			(end 0.12065 -0.3048)
			(stroke
				(width 0.1)
				(type default)
			)
			(layer "F.Fab")
		)
		(fp_line
			(start 0.12065 -0.3048)
			(end 0.67945 -0.3048)
			(stroke
				(width 0.1)
				(type default)
			)
			(layer "F.Fab")
		)
		(fp_line
			(start 0.120396 0.3048)
			(end 0.120396 0.2794)
			(stroke
				(width 0.1)
				(type default)
			)
			(layer "F.Fab")
		)
		(fp_line
			(start 0.120396 0.2794)
			(end -0.12065 0.2794)
			(stroke
				(width 0.1)
				(type default)
			)
			(layer "F.Fab")
		)
		(fp_line
			(start -0.12065 0.3048)
			(end -0.67945 0.3048)
			(stroke
				(width 0.1)
				(type default)
			)
			(layer "F.Fab")
		)
		(fp_line
			(start -0.12065 0.2794)
			(end -0.12065 0.3048)
			(stroke
				(width 0.1)
				(type default)
			)
			(layer "F.Fab")
		)
		(fp_line
			(start -0.12065 -0.2794)
			(end 0.12065 -0.2794)
			(stroke
				(width 0.1)
				(type default)
			)
			(layer "F.Fab")
		)
		(fp_line
			(start -0.12065 -0.305054)
			(end -0.12065 -0.2794)
			(stroke
				(width 0.1)
				(type default)
			)
			(layer "F.Fab")
		)
		(fp_line
			(start -0.67945 0.3048)
			(end -0.67945 -0.305054)
			(stroke
				(width 0.1)
				(type default)
			)
			(layer "F.Fab")
		)
		(fp_line
			(start -0.67945 -0.305054)
			(end -0.12065 -0.305054)
			(stroke
				(width 0.1)
				(type default)
			)
			(layer "F.Fab")
		)
		(pad "1" smd circle
			(at -0.40005 0 180)
			(size 0 0)
			(layers "F.Cu" "F.Mask" "F.Paste")
			(net "PEX_USB_HUB_PGANG")
		)
		(pad "2" smd circle
			(at 0.40005 0 180)
			(size 0 0)
			(layers "F.Cu" "F.Mask" "F.Paste")
			(net "GND")
		)
	)
	(footprint ""
		(layer "F.Cu")
		(at 130.419856 -170.599862 90)
		(property "Reference" "R1085"
			(at 0 0 90)
			(layer "F.SilkS")
			(hide yes)
			(effects
				(font
					(size 1.27 1.27)
				)
			)
		)
		(property "Value" ""
			(at 0 0 90)
			(layer "F.Fab")
			(effects
				(font
					(size 1.27 1.27)
				)
			)
		)
		(duplicate_pad_numbers_are_jumpers no)
		(fp_line
			(start -0.7874 -0.4064)
			(end 0.7874 -0.4064)
			(stroke
				(width 0.1524)
				(type default)
			)
			(layer "F.SilkS")
		)
		(fp_line
			(start -0.12065 -0.305054)
			(end -0.12065 -0.2794)
			(stroke
				(width 0.1)
				(type default)
			)
			(layer "F.Fab")
		)
		(fp_line
			(start -0.67945 -0.305054)
			(end -0.12065 -0.305054)
			(stroke
				(width 0.1)
				(type default)
			)
			(layer "F.Fab")
		)
		(fp_line
			(start 0.67945 -0.3048)
			(end 0.67945 0.3048)
			(stroke
				(width 0.1)
				(type default)
			)
			(layer "F.Fab")
		)
		(fp_line
			(start 0.12065 -0.3048)
			(end 0.67945 -0.3048)
			(stroke
				(width 0.1)
				(type default)
			)
			(layer "F.Fab")
		)
		(fp_line
			(start 0.12065 -0.2794)
			(end 0.12065 -0.3048)
			(stroke
				(width 0.1)
				(type default)
			)
			(layer "F.Fab")
		)
		(fp_line
			(start -0.12065 -0.2794)
			(end 0.12065 -0.2794)
			(stroke
				(width 0.1)
				(type default)
			)
			(layer "F.Fab")
		)
		(fp_line
			(start 0.120396 0.2794)
			(end -0.12065 0.2794)
			(stroke
				(width 0.1)
				(type default)
			)
			(layer "F.Fab")
		)
		(fp_line
			(start -0.12065 0.2794)
			(end -0.12065 0.3048)
			(stroke
				(width 0.1)
				(type default)
			)
			(layer "F.Fab")
		)
		(fp_line
			(start 0.67945 0.3048)
			(end 0.120396 0.3048)
			(stroke
				(width 0.1)
				(type default)
			)
			(layer "F.Fab")
		)
		(fp_line
			(start 0.120396 0.3048)
			(end 0.120396 0.2794)
			(stroke
				(width 0.1)
				(type default)
			)
			(layer "F.Fab")
		)
		(fp_line
			(start -0.12065 0.3048)
			(end -0.67945 0.3048)
			(stroke
				(width 0.1)
				(type default)
			)
			(layer "F.Fab")
		)
		(fp_line
			(start -0.67945 0.3048)
			(end -0.67945 -0.305054)
			(stroke
				(width 0.1)
				(type default)
			)
			(layer "F.Fab")
		)
		(pad "1" smd circle
			(at -0.40005 0 90)
			(size 0 0)
			(layers "F.Cu" "F.Mask" "F.Paste")
			(net "CLK_100M_DB2000QL_PEX3_S1_R_DP")
		)
		(pad "2" smd circle
			(at 0.40005 0 90)
			(size 0 0)
			(layers "F.Cu" "F.Mask" "F.Paste")
			(net "CLK_100M_DB2000QL_PEX3_S1_DP")
		)
	)
	(footprint ""
		(layer "F.Cu")
		(at 121.750328 -50.96383 180)
		(property "Reference" "PC503"
			(at 0 0 180)
			(layer "F.SilkS")
			(hide yes)
			(effects
				(font
					(size 1.27 1.27)
				)
			)
		)
		(property "Value" ""
			(at 0 0 180)
			(layer "F.Fab")
			(effects
				(font
					(size 1.27 1.27)
				)
			)
		)
		(duplicate_pad_numbers_are_jumpers no)
		(fp_line
			(start 1.524 0.762)
			(end -1.524 0.762)
			(stroke
				(width 0.1524)
				(type default)
			)
			(layer "F.SilkS")
		)
		(fp_line
			(start 1.524 -0.762)
			(end 1.524 0.762)
			(stroke
				(width 0.1524)
				(type default)
			)
			(layer "F.SilkS")
		)
		(fp_line
			(start -1.524 0.762)
			(end -1.524 -0.762)
			(stroke
				(width 0.1524)
				(type default)
			)
			(layer "F.SilkS")
		)
		(fp_line
			(start -1.524 -0.762)
			(end 1.524 -0.762)
			(stroke
				(width 0.1524)
				(type default)
			)
			(layer "F.SilkS")
		)
		(fp_line
			(start 1.1049 0.724916)
			(end 1.1049 -0.724916)
			(stroke
				(width 0.1)
				(type default)
			)
			(layer "F.Fab")
		)
		(fp_line
			(start 1.1049 -0.724916)
			(end -1.1049 -0.724916)
			(stroke
				(width 0.1)
				(type default)
			)
			(layer "F.Fab")
		)
		(fp_line
			(start -1.1049 0.724916)
			(end 1.1049 0.724916)
			(stroke
				(width 0.1)
				(type default)
			)
			(layer "F.Fab")
		)
		(fp_line
			(start -1.1049 -0.724916)
			(end -1.1049 0.724916)
			(stroke
				(width 0.1)
				(type default)
			)
			(layer "F.Fab")
		)
		(pad "1" smd rect
			(at -0.889 0)
			(size 1.016 1.27)
			(layers "F.Cu" "F.Mask" "F.Paste")
			(net "P3V3_SSD4")
		)
		(pad "2" smd rect
			(at 0.889 0)
			(size 1.016 1.27)
			(layers "F.Cu" "F.Mask" "F.Paste")
			(net "GND")
		)
	)
	(footprint ""
		(layer "F.Cu")
		(at 229.358444 -273.056858 90)
		(property "Reference" "C4295"
			(at 0 0 90)
			(layer "F.SilkS")
			(hide yes)
			(effects
				(font
					(size 1.27 1.27)
				)
			)
		)
		(property "Value" ""
			(at 0 0 90)
			(layer "F.Fab")
			(effects
				(font
					(size 1.27 1.27)
				)
			)
		)
		(duplicate_pad_numbers_are_jumpers no)
		(fp_line
			(start 0.299974 -0.150114)
			(end 0.299974 0.150114)
			(stroke
				(width 0.1)
				(type default)
			)
			(layer "F.Fab")
		)
		(fp_line
			(start -0.299974 -0.150114)
			(end 0.299974 -0.150114)
			(stroke
				(width 0.1)
				(type default)
			)
			(layer "F.Fab")
		)
		(fp_line
			(start 0.299974 0.150114)
			(end -0.299974 0.150114)
			(stroke
				(width 0.1)
				(type default)
			)
			(layer "F.Fab")
		)
		(fp_line
			(start -0.299974 0.150114)
			(end -0.299974 -0.150114)
			(stroke
				(width 0.1)
				(type default)
			)
			(layer "F.Fab")
		)
		(pad "1" smd rect
			(at -0.2667 0 90)
			(size 0.3048 0.381)
			(layers "F.Cu" "F.Mask" "F.Paste")
			(net "P1V25_SERDES_VDDPLL_PEX1")
		)
		(pad "2" smd rect
			(at 0.2667 0 90)
			(size 0.3048 0.381)
			(layers "F.Cu" "F.Mask" "F.Paste")
			(net "GND")
		)
	)
)
